(kicad_pcb
	(version 20240108)
	(generator "pcbnew")
	(generator_version "8.0")
	(general
		(thickness 1.62)
		(legacy_teardrops no)
	)
	(paper "A4")
	(title_block
		(title "Jetson Orin Baseboard")
		(date "2025-03-12")
		(rev "1.3.4")
		(company "Antmicro Ltd")
		(comment 1 "www.antmicro.com")
		(comment 9 "footprints 439-443 of 677")
	)
	(layers
		(0 "F.Cu" signal)
		(1 "In1.Cu" signal)
		(2 "In2.Cu" signal)
		(3 "In3.Cu" signal)
		(4 "In4.Cu" jumper)
		(5 "In5.Cu" signal)
		(6 "In6.Cu" signal)
		(31 "B.Cu" signal)
		(32 "B.Adhes" user "B.Adhesive")
		(33 "F.Adhes" user "F.Adhesive")
		(34 "B.Paste" user)
		(35 "F.Paste" user)
		(36 "B.SilkS" user "B.Silkscreen")
		(37 "F.SilkS" user "F.Silkscreen")
		(38 "B.Mask" user)
		(39 "F.Mask" user)
		(40 "Dwgs.User" user "User.Drawings")
		(41 "Cmts.User" user "User.Comments")
		(42 "Eco1.User" user "User.Eco1")
		(43 "Eco2.User" user "User.Eco2")
		(44 "Edge.Cuts" user)
		(45 "Margin" user)
		(46 "B.CrtYd" user "B.Courtyard")
		(47 "F.CrtYd" user "F.Courtyard")
		(48 "B.Fab" user)
		(49 "F.Fab" user)
	)
	(footprint "antmicro-footprints:C_0402_1005Metric"
		(layer "B.Cu")
		(at 60.07 86.31 180)
		(descr "Capacitor SMD 0402")
		(tags "capacitor SMD 0402")
		(property "Reference" "C83"
			(at -1.1 -1.4 0)
			(layer "B.SilkS")
			(effects
				(font
					(size 0.7 0.7)
					(thickness 0.15)
				)
				(justify left bottom mirror)
			)
		)
		(property "Value" "C_10u_0402"
			(at -1.022927 -2.155213 0)
			(layer "B.Fab")
			(effects
				(font
					(size 0.7 0.7)
					(thickness 0.15)
				)
				(justify left bottom mirror)
			)
		)
		(property "Footprint" "antmicro-footprints:C_0402_1005Metric"
			(at 0 0 180)
			(layer "F.Fab")
			(hide yes)
			(effects
				(font
					(size 1.27 1.27)
					(thickness 0.15)
				)
			)
		)
		(property "Datasheet" "https://www.yageo.com/en/Chart/Download/pdf/CC0402MRX5R5BB106"
			(at 0 0 180)
			(layer "F.Fab")
			(hide yes)
			(effects
				(font
					(size 1.27 1.27)
					(thickness 0.15)
				)
			)
		)
		(property "Author" "Antmicro"
			(at 120.14 172.62 0)
			(layer "B.Fab")
			(hide yes)
			(effects
				(font
					(size 1 1)
					(thickness 0.15)
				)
				(justify mirror)
			)
		)
		(property "Dielectric" ""
			(at 120.14 172.62 0)
			(layer "B.Fab")
			(hide yes)
			(effects
				(font
					(size 1 1)
					(thickness 0.15)
				)
				(justify mirror)
			)
		)
		(property "License" "Apache-2.0"
			(at 120.14 172.62 0)
			(layer "B.Fab")
			(hide yes)
			(effects
				(font
					(size 1 1)
					(thickness 0.15)
				)
				(justify mirror)
			)
		)
		(property "MPN" "CC0402MRX5R5BB106"
			(at 120.14 172.62 0)
			(layer "B.Fab")
			(hide yes)
			(effects
				(font
					(size 1 1)
					(thickness 0.15)
				)
				(justify mirror)
			)
		)
		(property "Manufacturer" "YAGEO"
			(at 120.14 172.62 0)
			(layer "B.Fab")
			(hide yes)
			(effects
				(font
					(size 1 1)
					(thickness 0.15)
				)
				(justify mirror)
			)
		)
		(property "Val" "10u"
			(at 120.14 172.62 0)
			(layer "B.Fab")
			(hide yes)
			(effects
				(font
					(size 1 1)
					(thickness 0.15)
				)
				(justify mirror)
			)
		)
		(property "Voltage" ""
			(at 120.14 172.62 0)
			(layer "B.Fab")
			(hide yes)
			(effects
				(font
					(size 1 1)
					(thickness 0.15)
				)
				(justify mirror)
			)
		)
		(sheetname "Supply")
		(sheetfile "supply.kicad_sch")
		(attr smd)
		(fp_rect
			(start -0.925 0.47)
			(end 0.925 -0.47)
			(stroke
				(width 0.05)
				(type default)
			)
			(fill none)
			(layer "B.CrtYd")
		)
		(fp_line
			(start 0.504 0.25)
			(end -0.494 0.25)
			(stroke
				(width 0.15)
				(type solid)
			)
			(layer "B.Fab")
		)
		(fp_line
			(start 0.504 -0.248)
			(end 0.504 0.25)
			(stroke
				(width 0.15)
				(type solid)
			)
			(layer "B.Fab")
		)
		(fp_line
			(start -0.494 0.25)
			(end -0.494 -0.248)
			(stroke
				(width 0.15)
				(type solid)
			)
			(layer "B.Fab")
		)
		(fp_line
			(start -0.494 -0.248)
			(end 0.504 -0.248)
			(stroke
				(width 0.15)
				(type solid)
			)
			(layer "B.Fab")
		)
		(fp_text user "${REFERENCE}"
			(at -0.939 -4.599 0)
			(layer "B.Fab")
			(hide yes)
			(effects
				(font
					(size 0.7 0.7)
					(thickness 0.15)
				)
				(justify left bottom mirror)
			)
		)
		(fp_text user "Author: Antmicro"
			(at -0.939 -3.399 0)
			(layer "B.Fab")
			(hide yes)
			(effects
				(font
					(size 0.7 0.7)
					(thickness 0.15)
				)
				(justify left bottom mirror)
			)
		)
		(fp_text user "License: Apache-2.0"
			(at -0.939 -5.799 0)
			(layer "B.Fab")
			(hide yes)
			(effects
				(font
					(size 0.7 0.7)
					(thickness 0.15)
				)
				(justify left bottom mirror)
			)
		)
		(pad "1" smd roundrect
			(at -0.48 0 180)
			(size 0.59 0.64)
			(layers "B.Cu" "B.Paste" "B.Mask")
			(roundrect_rratio 0.25)
			(net 99 "+5V")
			(pintype "passive")
		)
		(pad "2" smd roundrect
			(at 0.48 0 180)
			(size 0.59 0.64)
			(layers "B.Cu" "B.Paste" "B.Mask")
			(roundrect_rratio 0.25)
			(net 1 "GND")
			(pintype "passive")
		)
	)
	(footprint "antmicro-footprints:R_0402_1005Metric"
		(layer "B.Cu")
		(at 73.9 101)
		(descr "Resistor SMD 0402")
		(tags "resistor SMD 0402")
		(property "Reference" "R68"
			(at 0.93 -1.54 180)
			(layer "B.SilkS")
			(effects
				(font
					(size 0.7 0.7)
					(thickness 0.15)
				)
				(justify left bottom mirror)
			)
		)
		(property "Value" "R_200R_0402"
			(at 0 -1.4 180)
			(layer "B.Fab")
			(effects
				(font
					(size 0.7 0.7)
					(thickness 0.15)
				)
				(justify left bottom mirror)
			)
		)
		(property "Footprint" "antmicro-footprints:R_0402_1005Metric"
			(at 0 0 0)
			(layer "F.Fab")
			(hide yes)
			(effects
				(font
					(size 1.27 1.27)
					(thickness 0.15)
				)
			)
		)
		(property "Datasheet" "https://www.bourns.com/docs/product-datasheets/cr.pdf"
			(at 0 0 0)
			(layer "F.Fab")
			(hide yes)
			(effects
				(font
					(size 1.27 1.27)
					(thickness 0.15)
				)
			)
		)
		(property "Author" "Antmicro"
			(at 0 0 0)
			(layer "B.Fab")
			(hide yes)
			(effects
				(font
					(size 1 1)
					(thickness 0.15)
				)
				(justify mirror)
			)
		)
		(property "License" "Apache-2.0"
			(at 0 0 0)
			(layer "B.Fab")
			(hide yes)
			(effects
				(font
					(size 1 1)
					(thickness 0.15)
				)
				(justify mirror)
			)
		)
		(property "MPN" "CR0402-FX-2000GLF"
			(at 0 0 0)
			(layer "B.Fab")
			(hide yes)
			(effects
				(font
					(size 1 1)
					(thickness 0.15)
				)
				(justify mirror)
			)
		)
		(property "Manufacturer" "Bourns"
			(at 0 0 0)
			(layer "B.Fab")
			(hide yes)
			(effects
				(font
					(size 1 1)
					(thickness 0.15)
				)
				(justify mirror)
			)
		)
		(property "Tolerance" "1%"
			(at 0 0 0)
			(layer "B.Fab")
			(hide yes)
			(effects
				(font
					(size 1 1)
					(thickness 0.15)
				)
				(justify mirror)
			)
		)
		(property "Val" "200R"
			(at 0 0 0)
			(layer "B.Fab")
			(hide yes)
			(effects
				(font
					(size 1 1)
					(thickness 0.15)
				)
				(justify mirror)
			)
		)
		(sheetname "USB Debug, DP")
		(sheetfile "usb.kicad_sch")
		(attr smd)
		(fp_rect
			(start -0.925 0.47)
			(end 0.925 -0.47)
			(stroke
				(width 0.05)
				(type default)
			)
			(fill none)
			(layer "B.CrtYd")
		)
		(fp_rect
			(start -0.5 0.25)
			(end 0.5 -0.25)
			(stroke
				(width 0.15)
				(type solid)
			)
			(fill none)
			(layer "B.Fab")
		)
		(fp_text user "Author: Antmicro"
			(at -0.95 -4.169 180)
			(layer "B.Fab")
			(hide yes)
			(effects
				(font
					(size 0.7 0.7)
					(thickness 0.15)
				)
				(justify left bottom mirror)
			)
		)
		(fp_text user "License: Apache-2.0"
			(at -0.95 -5.169 180)
			(layer "B.Fab")
			(hide yes)
			(effects
				(font
					(size 0.7 0.7)
					(thickness 0.15)
				)
				(justify left bottom mirror)
			)
		)
		(fp_text user "${REFERENCE}"
			(at -0.95 -3.168 180)
			(layer "B.Fab")
			(hide yes)
			(effects
				(font
					(size 0.7 0.7)
					(thickness 0.15)
				)
				(justify left bottom mirror)
			)
		)
		(pad "1" smd roundrect
			(at -0.48 0)
			(size 0.59 0.64)
			(layers "B.Cu" "B.Paste" "B.Mask")
			(roundrect_rratio 0.25)
			(net 300 "/USB Debug, DP/PDC_GPIO14")
			(pintype "passive")
		)
		(pad "2" smd roundrect
			(at 0.48 0)
			(size 0.59 0.64)
			(layers "B.Cu" "B.Paste" "B.Mask")
			(roundrect_rratio 0.25)
			(net 144 "Net-(D4-A)")
			(pintype "passive")
		)
	)
	(footprint "antmicro-footprints:C_0402_1005Metric"
		(layer "B.Cu")
		(at 74.35 114.25 180)
		(descr "Capacitor SMD 0402")
		(tags "capacitor SMD 0402")
		(property "Reference" "C149"
			(at 0.86 -0.32 0)
			(layer "B.SilkS")
			(effects
				(font
					(size 0.7 0.7)
					(thickness 0.15)
				)
				(justify left bottom mirror)
			)
		)
		(property "Value" "C_1u_25V_0402"
			(at 0 -1.4 0)
			(layer "B.Fab")
			(effects
				(font
					(size 0.7 0.7)
					(thickness 0.15)
				)
				(justify left bottom mirror)
			)
		)
		(property "Footprint" "antmicro-footprints:C_0402_1005Metric"
			(at 0 0 180)
			(layer "F.Fab")
			(hide yes)
			(effects
				(font
					(size 1.27 1.27)
					(thickness 0.15)
				)
			)
		)
		(property "Datasheet" "https://www.murata.com/products/productdetail?partno=GRM155R61E105KE11%23"
			(at 0 0 180)
			(layer "F.Fab")
			(hide yes)
			(effects
				(font
					(size 1.27 1.27)
					(thickness 0.15)
				)
			)
		)
		(property "Author" "Antmicro"
			(at 148.7 228.5 0)
			(layer "B.Fab")
			(hide yes)
			(effects
				(font
					(size 1 1)
					(thickness 0.15)
				)
				(justify mirror)
			)
		)
		(property "Dielectric" "X5R"
			(at 148.7 228.5 0)
			(layer "B.Fab")
			(hide yes)
			(effects
				(font
					(size 1 1)
					(thickness 0.15)
				)
				(justify mirror)
			)
		)
		(property "License" "Apache-2.0"
			(at 148.7 228.5 0)
			(layer "B.Fab")
			(hide yes)
			(effects
				(font
					(size 1 1)
					(thickness 0.15)
				)
				(justify mirror)
			)
		)
		(property "MPN" "GRM155R61E105KE11J"
			(at 148.7 228.5 0)
			(layer "B.Fab")
			(hide yes)
			(effects
				(font
					(size 1 1)
					(thickness 0.15)
				)
				(justify mirror)
			)
		)
		(property "Manufacturer" "Murata"
			(at 148.7 228.5 0)
			(layer "B.Fab")
			(hide yes)
			(effects
				(font
					(size 1 1)
					(thickness 0.15)
				)
				(justify mirror)
			)
		)
		(property "Val" "1u"
			(at 148.7 228.5 0)
			(layer "B.Fab")
			(hide yes)
			(effects
				(font
					(size 1 1)
					(thickness 0.15)
				)
				(justify mirror)
			)
		)
		(property "Voltage" "25V"
			(at 148.7 228.5 0)
			(layer "B.Fab")
			(hide yes)
			(effects
				(font
					(size 1 1)
					(thickness 0.15)
				)
				(justify mirror)
			)
		)
		(sheetname "USB Debug, DP")
		(sheetfile "usb.kicad_sch")
		(attr smd)
		(fp_rect
			(start -0.925 0.47)
			(end 0.925 -0.47)
			(stroke
				(width 0.05)
				(type default)
			)
			(fill none)
			(layer "B.CrtYd")
		)
		(fp_line
			(start 0.504 0.25)
			(end -0.494 0.25)
			(stroke
				(width 0.15)
				(type solid)
			)
			(layer "B.Fab")
		)
		(fp_line
			(start 0.504 -0.248)
			(end 0.504 0.25)
			(stroke
				(width 0.15)
				(type solid)
			)
			(layer "B.Fab")
		)
		(fp_line
			(start -0.494 0.25)
			(end -0.494 -0.248)
			(stroke
				(width 0.15)
				(type solid)
			)
			(layer "B.Fab")
		)
		(fp_line
			(start -0.494 -0.248)
			(end 0.504 -0.248)
			(stroke
				(width 0.15)
				(type solid)
			)
			(layer "B.Fab")
		)
		(fp_text user "License: Apache-2.0"
			(at -0.932 -5.17 0)
			(layer "B.Fab")
			(hide yes)
			(effects
				(font
					(size 0.7 0.7)
					(thickness 0.15)
				)
				(justify left bottom mirror)
			)
		)
		(fp_text user "Author: Antmicro"
			(at -0.932 -4.17 0)
			(layer "B.Fab")
			(hide yes)
			(effects
				(font
					(size 0.7 0.7)
					(thickness 0.15)
				)
				(justify left bottom mirror)
			)
		)
		(fp_text user "${REFERENCE}"
			(at -0.932 -3.168 0)
			(layer "B.Fab")
			(hide yes)
			(effects
				(font
					(size 0.7 0.7)
					(thickness 0.15)
				)
				(justify left bottom mirror)
			)
		)
		(pad "1" smd roundrect
			(at -0.48 0 180)
			(size 0.59 0.64)
			(layers "B.Cu" "B.Paste" "B.Mask")
			(roundrect_rratio 0.25)
			(net 1 "GND")
			(pintype "passive")
		)
		(pad "2" smd roundrect
			(at 0.48 0 180)
			(size 0.59 0.64)
			(layers "B.Cu" "B.Paste" "B.Mask")
			(roundrect_rratio 0.25)
			(net 261 "/USB Debug, DP/USBC0_VBUS")
			(pintype "passive")
		)
	)
	(footprint "antmicro-footprints:C_0402_1005Metric"
		(layer "B.Cu")
		(at 138 104.5 -90)
		(descr "Capacitor SMD 0402")
		(tags "capacitor SMD 0402")
		(property "Reference" "C94"
			(at -1.1 -1.3 90)
			(layer "B.SilkS")
			(effects
				(font
					(size 0.7 0.7)
					(thickness 0.15)
				)
				(justify left bottom mirror)
			)
		)
		(property "Value" "C_1u_0402"
			(at 0 -1.4 90)
			(layer "B.Fab")
			(effects
				(font
					(size 0.7 0.7)
					(thickness 0.15)
				)
				(justify left bottom mirror)
			)
		)
		(property "Footprint" "antmicro-footprints:C_0402_1005Metric"
			(at 0 0 -90)
			(layer "F.Fab")
			(hide yes)
			(effects
				(font
					(size 1.27 1.27)
					(thickness 0.15)
				)
			)
		)
		(property "Datasheet" "https://product.tdk.com/en/search/capacitor/ceramic/mlcc/info?part_no=C1005X6S1A105K050BC"
			(at 0 0 -90)
			(layer "F.Fab")
			(hide yes)
			(effects
				(font
					(size 1.27 1.27)
					(thickness 0.15)
				)
			)
		)
		(property "Author" "Antmicro"
			(at 33.5 242.5 0)
			(layer "B.Fab")
			(hide yes)
			(effects
				(font
					(size 1 1)
					(thickness 0.15)
				)
				(justify mirror)
			)
		)
		(property "Dielectric" ""
			(at 33.5 242.5 0)
			(layer "B.Fab")
			(hide yes)
			(effects
				(font
					(size 1 1)
					(thickness 0.15)
				)
				(justify mirror)
			)
		)
		(property "License" "Apache-2.0"
			(at 33.5 242.5 0)
			(layer "B.Fab")
			(hide yes)
			(effects
				(font
					(size 1 1)
					(thickness 0.15)
				)
				(justify mirror)
			)
		)
		(property "MPN" "C1005X6S1A105K050BC"
			(at 33.5 242.5 0)
			(layer "B.Fab")
			(hide yes)
			(effects
				(font
					(size 1 1)
					(thickness 0.15)
				)
				(justify mirror)
			)
		)
		(property "Manufacturer" "TDK"
			(at 33.5 242.5 0)
			(layer "B.Fab")
			(hide yes)
			(effects
				(font
					(size 1 1)
					(thickness 0.15)
				)
				(justify mirror)
			)
		)
		(property "Val" "1u"
			(at 33.5 242.5 0)
			(layer "B.Fab")
			(hide yes)
			(effects
				(font
					(size 1 1)
					(thickness 0.15)
				)
				(justify mirror)
			)
		)
		(property "Voltage" ""
			(at 33.5 242.5 0)
			(layer "B.Fab")
			(hide yes)
			(effects
				(font
					(size 1 1)
					(thickness 0.15)
				)
				(justify mirror)
			)
		)
		(sheetname "CSI")
		(sheetfile "csi.kicad_sch")
		(attr smd)
		(fp_rect
			(start -0.925 0.47)
			(end 0.925 -0.47)
			(stroke
				(width 0.05)
				(type default)
			)
			(fill none)
			(layer "B.CrtYd")
		)
		(fp_line
			(start -0.494 0.25)
			(end -0.494 -0.248)
			(stroke
				(width 0.15)
				(type solid)
			)
			(layer "B.Fab")
		)
		(fp_line
			(start 0.504 0.25)
			(end -0.494 0.25)
			(stroke
				(width 0.15)
				(type solid)
			)
			(layer "B.Fab")
		)
		(fp_line
			(start -0.494 -0.248)
			(end 0.504 -0.248)
			(stroke
				(width 0.15)
				(type solid)
			)
			(layer "B.Fab")
		)
		(fp_line
			(start 0.504 -0.248)
			(end 0.504 0.25)
			(stroke
				(width 0.15)
				(type solid)
			)
			(layer "B.Fab")
		)
		(fp_text user "${REFERENCE}"
			(at -0.932 -3.168 90)
			(layer "B.Fab")
			(hide yes)
			(effects
				(font
					(size 0.7 0.7)
					(thickness 0.15)
				)
				(justify left bottom mirror)
			)
		)
		(fp_text user "Author: Antmicro"
			(at -0.932 -4.17 90)
			(layer "B.Fab")
			(hide yes)
			(effects
				(font
					(size 0.7 0.7)
					(thickness 0.15)
				)
				(justify left bottom mirror)
			)
		)
		(fp_text user "License: Apache-2.0"
			(at -0.932 -5.17 90)
			(layer "B.Fab")
			(hide yes)
			(effects
				(font
					(size 0.7 0.7)
					(thickness 0.15)
				)
				(justify left bottom mirror)
			)
		)
		(pad "1" smd roundrect
			(at -0.48 0 270)
			(size 0.59 0.64)
			(layers "B.Cu" "B.Paste" "B.Mask")
			(roundrect_rratio 0.25)
			(net 1 "GND")
			(pintype "passive")
		)
		(pad "2" smd roundrect
			(at 0.48 0 270)
			(size 0.59 0.64)
			(layers "B.Cu" "B.Paste" "B.Mask")
			(roundrect_rratio 0.25)
			(net 108 "/CSI/CSIA_3V3")
			(pintype "passive")
		)
	)
	(footprint "antmicro-footprints:R_0402_1005Metric"
		(layer "B.Cu")
		(at 77.6 107.4 180)
		(descr "Resistor SMD 0402")
		(tags "resistor SMD 0402")
		(property "Reference" "R90"
			(at -3.14 -2.38 0)
			(layer "B.SilkS")
			(effects
				(font
					(size 0.7 0.7)
					(thickness 0.15)
				)
				(justify left bottom mirror)
			)
		)
		(property "Value" "R_1k_0402"
			(at 0 -1.4 0)
			(layer "B.Fab")
			(effects
				(font
					(size 0.7 0.7)
					(thickness 0.15)
				)
				(justify left bottom mirror)
			)
		)
		(property "Footprint" "antmicro-footprints:R_0402_1005Metric"
			(at 0 0 180)
			(layer "F.Fab")
			(hide yes)
			(effects
				(font
					(size 1.27 1.27)
					(thickness 0.15)
				)
			)
		)
		(property "Datasheet" "https://www.bourns.com/docs/product-datasheets/cr.pdf"
			(at 0 0 180)
			(layer "F.Fab")
			(hide yes)
			(effects
				(font
					(size 1.27 1.27)
					(thickness 0.15)
				)
			)
		)
		(property "Author" "Antmicro"
			(at 155.2 214.8 0)
			(layer "B.Fab")
			(hide yes)
			(effects
				(font
					(size 1 1)
					(thickness 0.15)
				)
				(justify mirror)
			)
		)
		(property "License" "Apache-2.0"
			(at 155.2 214.8 0)
			(layer "B.Fab")
			(hide yes)
			(effects
				(font
					(size 1 1)
					(thickness 0.15)
				)
				(justify mirror)
			)
		)
		(property "MPN" "CR0402-FX-1001GLF"
			(at 155.2 214.8 0)
			(layer "B.Fab")
			(hide yes)
			(effects
				(font
					(size 1 1)
					(thickness 0.15)
				)
				(justify mirror)
			)
		)
		(property "Manufacturer" "Bourns"
			(at 155.2 214.8 0)
			(layer "B.Fab")
			(hide yes)
			(effects
				(font
					(size 1 1)
					(thickness 0.15)
				)
				(justify mirror)
			)
		)
		(property "Tolerance" "1%"
			(at 155.2 214.8 0)
			(layer "B.Fab")
			(hide yes)
			(effects
				(font
					(size 1 1)
					(thickness 0.15)
				)
				(justify mirror)
			)
		)
		(property "Val" "1k"
			(at 155.2 214.8 0)
			(layer "B.Fab")
			(hide yes)
			(effects
				(font
					(size 1 1)
					(thickness 0.15)
				)
				(justify mirror)
			)
		)
		(sheetname "USB Debug, DP")
		(sheetfile "usb.kicad_sch")
		(attr smd)
		(fp_rect
			(start -0.925 0.47)
			(end 0.925 -0.47)
			(stroke
				(width 0.05)
				(type default)
			)
			(fill none)
			(layer "B.CrtYd")
		)
		(fp_rect
			(start -0.5 0.25)
			(end 0.5 -0.25)
			(stroke
				(width 0.15)
				(type solid)
			)
			(fill none)
			(layer "B.Fab")
		)
		(fp_text user "License: Apache-2.0"
			(at -0.95 -5.169 0)
			(layer "B.Fab")
			(hide yes)
			(effects
				(font
					(size 0.7 0.7)
					(thickness 0.15)
				)
				(justify left bottom mirror)
			)
		)
		(fp_text user "Author: Antmicro"
			(at -0.95 -4.169 0)
			(layer "B.Fab")
			(hide yes)
			(effects
				(font
					(size 0.7 0.7)
					(thickness 0.15)
				)
				(justify left bottom mirror)
			)
		)
		(fp_text user "${REFERENCE}"
			(at -0.95 -3.168 0)
			(layer "B.Fab")
			(hide yes)
			(effects
				(font
					(size 0.7 0.7)
					(thickness 0.15)
				)
				(justify left bottom mirror)
			)
		)
		(pad "1" smd roundrect
			(at -0.48 0 180)
			(size 0.59 0.64)
			(layers "B.Cu" "B.Paste" "B.Mask")
			(roundrect_rratio 0.25)
			(net 306 "/USB Debug, DP/USBC0_SSEQ1")
			(pintype "passive")
		)
		(pad "2" smd roundrect
			(at 0.48 0 180)
			(size 0.59 0.64)
			(layers "B.Cu" "B.Paste" "B.Mask")
			(roundrect_rratio 0.25)
			(net 1 "GND")
			(pintype "passive")
		)
	)
)
